FILE_TYPE = MACRO_DRAWING;
SET COLOR_WIRE YELLOW;
SET COLOR_PROP MONO;
SET COLOR_DOT WHITE;
SET COLOR_ARC YELLOW;
SET COLOR_BODY GREEN;
SET COLOR_NOTE MONO;
SET PROP_DISPLAY VALUE;
SET PAGE_NUMBER P126;
FORCEADD RES..2
(-6325 4175);
FORCEPROP 1 LASTPIN (-6325 4075) $PN 2
J 0
(-6320 4085);
DISPLAY 0.617021 (-6320 4085);
PAINT ORANGE (-6320 4085);
FORCEPROP 1 LASTPIN (-6325 4275) $PN 1
J 0
(-6320 4237);
DISPLAY 0.617021 (-6320 4237);
PAINT ORANGE (-6320 4237);
FORCEPROP 1 LAST WATTAGE 1/16W
J 0
(-6285 4150);
DISPLAY 0.617021 (-6285 4150);
PAINT SKYBLUE (-6285 4150);
FORCEPROP 1 LAST MATERIAL CHIP
J 0
(-6285 4100);
DISPLAY 0.617021 (-6285 4100);
PAINT SKYBLUE (-6285 4100);
FORCEPROP 1 LAST PACK_TYPE 0402
J 0
(-6285 4000);
DISPLAY 0.617021 (-6285 4000);
PAINT SKYBLUE (-6285 4000);
FORCEPROP 1 LAST TOLERANCE 1%
J 0
(-6280 4200);
DISPLAY 0.617021 (-6280 4200);
PAINT SKYBLUE (-6280 4200);
FORCEPROP 1 LAST VALUE 4.75K
J 0
(-6280 4250);
DISPLAY 0.617021 (-6280 4250);
PAINT SKYBLUE (-6280 4250);
FORCEPROP 1 LAST PART_NUMBER G21796-072
J 0
(-6285 4050);
DISPLAY 0.617021 (-6285 4050);
PAINT BLUE (-6285 4050);
FORCEPROP 1 LAST LOCATION R2N10
J 0
(-6275 4300);
DISPLAY 0.617021 (-6275 4300);
PAINT AQUA (-6275 4300);
FORCEPROP 2 LAST SEC_TYPE 0402
J 0
(-6275 4400);
DISPLAY 1.021277 (-6275 4400);
PAINT ORANGE (-6275 4400);
DISPLAY INVISIBLE (-6275 4400);
FORCEPROP 2 LAST SEC 1
J 0
(-6275 4400);
DISPLAY 0.680851 (-6275 4400);
PAINT MONO (-6275 4400);
DISPLAY INVISIBLE (-6275 4400);
FORCEPROP 2 LAST CDS_LIB mstr_discrete
J 0
(-6325 4175);
PAINT ORANGE (-6325 4175);
DISPLAY INVISIBLE (-6325 4175);
FORCEPROP 1 LAST PATH I10
J 0
(-6275 4350);
DISPLAY 0.978723 (-6275 4350);
PAINT WHITE (-6275 4350);
DISPLAY INVISIBLE (-6275 4350);
FORCEPROP 2 LAST BOM_COST SB
R 3
J 0
(-6125 4250);
PAINT ORANGE (-6125 4250);
DISPLAY INVISIBLE (-6125 4250);
FORCEPROP 2 LAST CDS_LOCATION R2N10
J 0
(-6275 4300);
DISPLAY 0.617021 (-6275 4300);
PAINT AQUA (-6275 4300);
DISPLAY INVISIBLE (-6275 4300);
FORCEPROP 2 LAST ROOM SB_HEADERS
R 3
J 0
(-6125 4250);
PAINT ORANGE (-6125 4250);
DISPLAY INVISIBLE (-6125 4250);
FORCEADD OFFPAGE..5
(-7350 4025);
FORCEPROP 2 LAST $XR1 134 
J 0
(-7725 4025);
DISPLAY 0.638298 (-7725 4025);
PAINT MONO (-7725 4025);
FORCEPROP 2 LAST $XR0 119 
J 0
(-7605 4025);
DISPLAY 0.638298 (-7605 4025);
PAINT MONO (-7605 4025);
FORCEPROP 1 LAST OFFPAGE TRUE
J 0
(-7025 3900);
DISPLAY 1.170213 (-7025 3900);
PAINT GREEN (-7025 3900);
DISPLAY INVISIBLE (-7025 3900);
FORCEPROP 2 LAST CDS_LIB mstr_standard
J 0
(-7350 4025);
PAINT ORANGE (-7350 4025);
DISPLAY INVISIBLE (-7350 4025);
FORCEPROP 1 LAST COMMENT_BODY TRUE
J 0
(-7250 3950);
DISPLAY 1.170213 (-7250 3950);
PAINT GREEN (-7250 3950);
DISPLAY INVISIBLE (-7250 3950);
FORCEPROP 2 LAST PATH I11
J 0
(-7300 4100);
DISPLAY 1.021277 (-7300 4100);
PAINT ORANGE (-7300 4100);
DISPLAY INVISIBLE (-7300 4100);
FORCEPROP 2 LAST ROOM SB
J 0
(-7625 4075);
DISPLAY 1.361702 (-7625 4075);
PAINT ORANGE (-7625 4075);
DISPLAY INVISIBLE (-7625 4075);
FORCEPROP 2 LAST BOM_COST SB
J 0
(-7625 4075);
DISPLAY 1.361702 (-7625 4075);
PAINT ORANGE (-7625 4075);
DISPLAY INVISIBLE (-7625 4075);
FORCEADD RES..2
(-6200 2775);
FORCEPROP 1 LASTPIN (-6200 2875) $PN 1
J 0
(-6195 2837);
DISPLAY 0.617021 (-6195 2837);
PAINT ORANGE (-6195 2837);
FORCEPROP 1 LASTPIN (-6200 2675) $PN 2
J 0
(-6195 2685);
DISPLAY 0.617021 (-6195 2685);
PAINT ORANGE (-6195 2685);
FORCEPROP 1 LAST PACK_TYPE 0402
J 0
(-6160 2600);
DISPLAY 0.617021 (-6160 2600);
PAINT SKYBLUE (-6160 2600);
FORCEPROP 1 LAST TOLERANCE 1%
J 0
(-6155 2800);
DISPLAY 0.617021 (-6155 2800);
PAINT SKYBLUE (-6155 2800);
FORCEPROP 1 LAST PART_NUMBER G21796-072
J 0
(-6160 2650);
DISPLAY 0.617021 (-6160 2650);
PAINT BLUE (-6160 2650);
FORCEPROP 1 LAST WATTAGE 1/16W
J 0
(-6160 2750);
DISPLAY 0.617021 (-6160 2750);
PAINT SKYBLUE (-6160 2750);
FORCEPROP 1 LAST VALUE 4.75K
J 0
(-6155 2850);
DISPLAY 0.617021 (-6155 2850);
PAINT SKYBLUE (-6155 2850);
FORCEPROP 1 LAST LOCATION R1D35
J 0
(-6155 2900);
DISPLAY 0.617021 (-6155 2900);
PAINT AQUA (-6155 2900);
FORCEPROP 1 LAST MATERIAL CHIP
J 0
(-6160 2700);
DISPLAY 0.617021 (-6160 2700);
PAINT SKYBLUE (-6160 2700);
FORCEPROP 1 LAST PATH I12
J 0
(-6150 2950);
DISPLAY 0.978723 (-6150 2950);
PAINT WHITE (-6150 2950);
DISPLAY INVISIBLE (-6150 2950);
FORCEPROP 2 LAST SEC 1
J 0
(-6150 3000);
DISPLAY 0.680851 (-6150 3000);
PAINT MONO (-6150 3000);
DISPLAY INVISIBLE (-6150 3000);
FORCEPROP 2 LAST SEC_TYPE 0402
J 0
(-6150 3000);
DISPLAY 1.021277 (-6150 3000);
PAINT ORANGE (-6150 3000);
DISPLAY INVISIBLE (-6150 3000);
FORCEPROP 2 LAST BOM_COST SM_CONTROLLER
J 0
(-6250 2925);
DISPLAY 1.021277 (-6250 2925);
PAINT ORANGE (-6250 2925);
DISPLAY INVISIBLE (-6250 2925);
FORCEPROP 2 LAST CDS_LOCATION R1D35
J 0
(-6155 2900);
DISPLAY 0.617021 (-6155 2900);
PAINT AQUA (-6155 2900);
DISPLAY INVISIBLE (-6155 2900);
FORCEPROP 2 LAST CDS_LIB mstr_discrete
J 0
(-6200 2775);
PAINT ORANGE (-6200 2775);
DISPLAY INVISIBLE (-6200 2775);
FORCEPROP 2 LAST ROOM BMC_MISC
J 0
(-6250 2875);
DISPLAY 1.021277 (-6250 2875);
PAINT ORANGE (-6250 2875);
DISPLAY INVISIBLE (-6250 2875);
FORCEADD FET_N..8
(-3625 3925);
FORCEPROP 1 LASTPIN (-3625 4125) $PN 3
J 2
(-3572 4090);
DISPLAY 0.617021 (-3572 4090);
PAINT WHITE (-3572 4090);
FORCEPROP 1 LASTPIN (-3625 3725) $PN 2
J 2
(-3567 3725);
DISPLAY 0.617021 (-3567 3725);
PAINT WHITE (-3567 3725);
FORCEPROP 1 LASTPIN (-3825 3825) $PN 1
J 2
(-3822 3840);
DISPLAY 0.617021 (-3822 3840);
PAINT WHITE (-3822 3840);
FORCEPROP 1 LAST MATERIAL FET
J 0
(-3425 3825);
DISPLAY 0.617021 (-3425 3825);
PAINT SKYBLUE (-3425 3825);
FORCEPROP 1 LAST VALUE 2N7002
J 0
(-3425 3875);
DISPLAY 0.617021 (-3425 3875);
PAINT SKYBLUE (-3425 3875);
FORCEPROP 1 LAST PART_NUMBER C79254-001
J 0
(-3425 3725);
DISPLAY 0.617021 (-3425 3725);
PAINT BLUE (-3425 3725);
FORCEPROP 1 LAST LOCATION Q8E2
J 0
(-3425 3925);
DISPLAY 0.617021 (-3425 3925);
PAINT AQUA (-3425 3925);
FORCEPROP 2 LAST SEC_TYPE SOT23LF
J 0
(-3425 4025);
DISPLAY 1.021277 (-3425 4025);
PAINT ORANGE (-3425 4025);
DISPLAY INVISIBLE (-3425 4025);
FORCEPROP 2 LAST SEC 1
J 0
(-3425 4025);
DISPLAY 0.680851 (-3425 4025);
PAINT MONO (-3425 4025);
DISPLAY INVISIBLE (-3425 4025);
FORCEPROP 1 LAST PATH I13
J 0
(-3425 3975);
DISPLAY 0.978723 (-3425 3975);
PAINT BLUE (-3425 3975);
DISPLAY INVISIBLE (-3425 3975);
FORCEPROP 2 LAST CDS_LIB mstr_discrete
J 0
(-3625 3925);
PAINT ORANGE (-3625 3925);
DISPLAY INVISIBLE (-3625 3925);
FORCEPROP 1 LAST PACK_TYPE SOT23LF
J 0
(-3425 3775);
DISPLAY 0.978723 (-3425 3775);
PAINT SKYBLUE (-3425 3775);
DISPLAY INVISIBLE (-3425 3775);
FORCEADD GND..1
(-3625 3575);
FORCEPROP 3 LASTPIN (-3625 3625) SIG_NAME GND\g
J 0
(-3615 3635);
DISPLAY 0.659574 (-3615 3635);
PAINT MONO (-3615 3635);
DISPLAY INVISIBLE (-3615 3635);
FORCEPROP 1 LAST PATH I14
J 0
(-3550 3575);
DISPLAY 0.872340 (-3550 3575);
PAINT AQUA (-3550 3575);
DISPLAY INVISIBLE (-3550 3575);
FORCEPROP 1 LAST SIZE 1B
J 0
(-3550 3525);
DISPLAY 1.170213 (-3550 3525);
PAINT AQUA (-3550 3525);
DISPLAY INVISIBLE (-3550 3525);
FORCEPROP 2 LAST BOM_COST SB
J 0
(-3600 3650);
DISPLAY 1.361702 (-3600 3650);
PAINT ORANGE (-3600 3650);
DISPLAY INVISIBLE (-3600 3650);
FORCEPROP 2 LAST CDS_LIB mstr_symbols
J 0
(-3625 3575);
PAINT ORANGE (-3625 3575);
DISPLAY INVISIBLE (-3625 3575);
FORCEPROP 1 LAST BODY_TYPE PLUMBING
J 0
(-3670 3532);
DISPLAY 0.340426 (-3670 3532);
PAINT GREEN (-3670 3532);
DISPLAY INVISIBLE (-3670 3532);
FORCEPROP 2 LAST ROOM SB
J 0
(-3600 3650);
DISPLAY 1.361702 (-3600 3650);
PAINT ORANGE (-3600 3650);
DISPLAY INVISIBLE (-3600 3650);
FORCEPROP 1 LAST HDL_POWER GND
J 0
(-3625 3725);
DISPLAY 1.170213 (-3625 3725);
PAINT GREEN (-3625 3725);
DISPLAY INVISIBLE (-3625 3725);
FORCEPROP 1 LAST VOLTAGE 0.0V
J 0
(-3670 3532);
DISPLAY 0.340426 (-3670 3532);
PAINT SKYBLUE (-3670 3532);
DISPLAY INVISIBLE (-3670 3532);
FORCEADD P3V3_STBY..1
(-3625 4650);
FORCEPROP 3 LASTPIN (-3625 4600) SIG_NAME P3V3_STBY\g
J 0
(-3615 4610);
DISPLAY 0.659574 (-3615 4610);
PAINT MONO (-3615 4610);
DISPLAY INVISIBLE (-3615 4610);
FORCEPROP 1 LAST PATH I16
J 0
(-3580 4652);
DISPLAY 0.340426 (-3580 4652);
PAINT GREEN (-3580 4652);
DISPLAY INVISIBLE (-3580 4652);
FORCEPROP 1 LAST SIZE 1B
J 0
(-3580 4672);
DISPLAY 0.340426 (-3580 4672);
PAINT GREEN (-3580 4672);
DISPLAY INVISIBLE (-3580 4672);
FORCEPROP 2 LAST CDS_LIB mstr_symbols
J 0
(-3625 4650);
PAINT ORANGE (-3625 4650);
DISPLAY INVISIBLE (-3625 4650);
FORCEPROP 1 LAST BODY_TYPE PLUMBING
J 0
(-3670 4607);
DISPLAY 0.340426 (-3670 4607);
PAINT GREEN (-3670 4607);
DISPLAY INVISIBLE (-3670 4607);
FORCEPROP 1 LAST HDL_POWER P3V3_STBY
J 0
(-3925 4525);
DISPLAY 0.872340 (-3925 4525);
PAINT ORANGE (-3925 4525);
DISPLAY INVISIBLE (-3925 4525);
FORCEPROP 1 LAST VOLTAGE 3.3V
J 0
(-3670 4607);
DISPLAY 0.340426 (-3670 4607);
PAINT SKYBLUE (-3670 4607);
DISPLAY INVISIBLE (-3670 4607);
FORCEADD OFFPAGE..2
(-2900 4225);
FORCEPROP 2 LAST $XR1 146 
J 0
(-2591 4225);
DISPLAY 0.638298 (-2591 4225);
PAINT MONO (-2591 4225);
FORCEPROP 2 LAST $XR0 119 
J 0
(-2711 4225);
DISPLAY 0.638298 (-2711 4225);
PAINT MONO (-2711 4225);
FORCEPROP 1 LAST COMMENT_BODY TRUE
J 0
(-2945 4130);
DISPLAY 1.170213 (-2945 4130);
PAINT GREEN (-2945 4130);
DISPLAY INVISIBLE (-2945 4130);
FORCEPROP 2 LAST CDS_LIB mstr_standard
J 0
(-2900 4225);
DISPLAY 1.361702 (-2900 4225);
PAINT ORANGE (-2900 4225);
DISPLAY INVISIBLE (-2900 4225);
FORCEPROP 2 LAST PATH I17
J 0
(-2575 4275);
DISPLAY 1.021277 (-2575 4275);
PAINT ORANGE (-2575 4275);
DISPLAY INVISIBLE (-2575 4275);
FORCEPROP 1 LAST OFFPAGE TRUE
J 0
(-2575 4100);
PAINT GREEN (-2575 4100);
DISPLAY INVISIBLE (-2575 4100);
FORCEADD RES..2
(-3625 4425);
FORCEPROP 1 LAST PACK_TYPE 0402
J 0
(-3585 4250);
DISPLAY 0.617021 (-3585 4250);
PAINT SKYBLUE (-3585 4250);
FORCEPROP 1 LASTPIN (-3625 4525) $PN 1
J 0
(-3620 4487);
DISPLAY 0.617021 (-3620 4487);
PAINT ORANGE (-3620 4487);
FORCEPROP 1 LASTPIN (-3625 4325) $PN 2
J 0
(-3620 4335);
DISPLAY 0.617021 (-3620 4335);
PAINT ORANGE (-3620 4335);
FORCEPROP 1 LAST WATTAGE 1/16W
J 0
(-3585 4400);
DISPLAY 0.617021 (-3585 4400);
PAINT SKYBLUE (-3585 4400);
FORCEPROP 1 LAST MATERIAL CHIP
J 0
(-3585 4350);
DISPLAY 0.617021 (-3585 4350);
PAINT SKYBLUE (-3585 4350);
FORCEPROP 1 LAST TOLERANCE 1%
J 0
(-3580 4450);
DISPLAY 0.617021 (-3580 4450);
PAINT SKYBLUE (-3580 4450);
FORCEPROP 1 LAST VALUE 4.75K
J 0
(-3580 4500);
DISPLAY 0.617021 (-3580 4500);
PAINT SKYBLUE (-3580 4500);
FORCEPROP 1 LAST PART_NUMBER G21796-072
J 0
(-3585 4300);
DISPLAY 0.617021 (-3585 4300);
PAINT BLUE (-3585 4300);
FORCEPROP 1 LAST LOCATION R8C9
J 0
(-3580 4550);
DISPLAY 0.617021 (-3580 4550);
PAINT AQUA (-3580 4550);
FORCEPROP 1 LAST PATH I20
J 0
(-3575 4600);
DISPLAY 0.978723 (-3575 4600);
PAINT WHITE (-3575 4600);
DISPLAY INVISIBLE (-3575 4600);
FORCEPROP 2 LAST CDS_LOCATION R8C9
J 0
(-3580 4550);
DISPLAY 0.617021 (-3580 4550);
PAINT AQUA (-3580 4550);
DISPLAY INVISIBLE (-3580 4550);
FORCEPROP 2 LAST SEC 1
J 0
(-3575 4650);
DISPLAY 0.680851 (-3575 4650);
PAINT MONO (-3575 4650);
DISPLAY INVISIBLE (-3575 4650);
FORCEPROP 2 LAST SEC_TYPE 0402
J 0
(-3575 4650);
DISPLAY 1.021277 (-3575 4650);
PAINT ORANGE (-3575 4650);
DISPLAY INVISIBLE (-3575 4650);
FORCEPROP 2 LAST BOM_COST SM_CONTROLLER
J 0
(-3675 4575);
DISPLAY 1.021277 (-3675 4575);
PAINT ORANGE (-3675 4575);
DISPLAY INVISIBLE (-3675 4575);
FORCEPROP 2 LAST CDS_LIB mstr_discrete
J 0
(-3625 4425);
PAINT MONO (-3625 4425);
DISPLAY INVISIBLE (-3625 4425);
FORCEPROP 2 LAST ROOM BMC_MISC
J 0
(-3675 4525);
DISPLAY 1.021277 (-3675 4525);
PAINT ORANGE (-3675 4525);
DISPLAY INVISIBLE (-3675 4525);
FORCEADD OFFPAGE..1
(-4475 3825);
FORCEPROP 2 LAST $XR0 190 
J 0
(-4757 3825);
DISPLAY 0.638298 (-4757 3825);
PAINT MONO (-4757 3825);
FORCEPROP 2 LAST PATH I21
J 0
(-4425 3900);
DISPLAY 1.021277 (-4425 3900);
PAINT ORANGE (-4425 3900);
DISPLAY INVISIBLE (-4425 3900);
FORCEPROP 2 LAST CDS_LIB mstr_standard
J 0
(-4475 3825);
PAINT ORANGE (-4475 3825);
DISPLAY INVISIBLE (-4475 3825);
FORCEPROP 1 LAST COMMENT_BODY TRUE
J 0
(-4350 3725);
DISPLAY 0.872340 (-4350 3725);
PAINT GREEN (-4350 3725);
DISPLAY INVISIBLE (-4350 3725);
FORCEPROP 1 LAST OFFPAGE TRUE
J 0
(-4150 3700);
DISPLAY 0.872340 (-4150 3700);
PAINT GREEN (-4150 3700);
DISPLAY INVISIBLE (-4150 3700);
FORCEADD RES..2
(-4525 2725);
FORCEPROP 1 LASTPIN (-4525 2825) $PN 1
J 0
(-4520 2787);
DISPLAY 0.617021 (-4520 2787);
PAINT ORANGE (-4520 2787);
FORCEPROP 1 LASTPIN (-4525 2625) $PN 2
J 0
(-4520 2635);
DISPLAY 0.617021 (-4520 2635);
PAINT ORANGE (-4520 2635);
FORCEPROP 1 LAST PACK_TYPE 0402
J 0
(-4485 2550);
DISPLAY 0.617021 (-4485 2550);
PAINT SKYBLUE (-4485 2550);
FORCEPROP 1 LAST TOLERANCE 1%
J 0
(-4480 2750);
DISPLAY 0.617021 (-4480 2750);
PAINT SKYBLUE (-4480 2750);
FORCEPROP 1 LAST VALUE 4.75K
J 0
(-4480 2800);
DISPLAY 0.617021 (-4480 2800);
PAINT SKYBLUE (-4480 2800);
FORCEPROP 1 LAST LOCATION R3P62
J 0
(-4480 2850);
DISPLAY 0.617021 (-4480 2850);
PAINT AQUA (-4480 2850);
FORCEPROP 1 LAST WATTAGE 1/16W
J 0
(-4485 2700);
DISPLAY 0.617021 (-4485 2700);
PAINT SKYBLUE (-4485 2700);
FORCEPROP 1 LAST MATERIAL EMPTY
J 0
(-4485 2650);
DISPLAY 0.617021 (-4485 2650);
PAINT RED (-4485 2650);
FORCEPROP 1 LAST PART_NUMBER G21796-072
J 0
(-4485 2600);
DISPLAY 0.617021 (-4485 2600);
PAINT BLUE (-4485 2600);
FORCEPROP 2 LAST SEC_TYPE 0402
J 0
(-4475 2950);
DISPLAY 1.021277 (-4475 2950);
PAINT ORANGE (-4475 2950);
DISPLAY INVISIBLE (-4475 2950);
FORCEPROP 0 LAST SEC 1
J 0
(-4475 2900);
DISPLAY 0.680851 (-4475 2900);
PAINT MONO (-4475 2900);
DISPLAY INVISIBLE (-4475 2900);
FORCEPROP 1 LAST PATH I22
J 0
(-4475 2900);
DISPLAY 0.978723 (-4475 2900);
PAINT WHITE (-4475 2900);
DISPLAY INVISIBLE (-4475 2900);
FORCEPROP 2 LAST CDS_LIB mstr_discrete
J 0
(-4525 2725);
PAINT ORANGE (-4525 2725);
DISPLAY INVISIBLE (-4525 2725);
FORCEADD RES..2
(-4525 2275);
FORCEPROP 1 LASTPIN (-4525 2375) $PN 1
J 0
(-4520 2337);
DISPLAY 0.617021 (-4520 2337);
PAINT ORANGE (-4520 2337);
FORCEPROP 1 LASTPIN (-4525 2175) $PN 2
J 0
(-4520 2185);
DISPLAY 0.617021 (-4520 2185);
PAINT ORANGE (-4520 2185);
FORCEPROP 1 LAST WATTAGE 1/16W
J 0
(-4485 2250);
DISPLAY 0.617021 (-4485 2250);
PAINT SKYBLUE (-4485 2250);
FORCEPROP 1 LAST PACK_TYPE 0402
J 0
(-4485 2100);
DISPLAY 0.617021 (-4485 2100);
PAINT SKYBLUE (-4485 2100);
FORCEPROP 1 LAST TOLERANCE 1%
J 0
(-4480 2300);
DISPLAY 0.617021 (-4480 2300);
PAINT SKYBLUE (-4480 2300);
FORCEPROP 1 LAST VALUE 1.00K
J 0
(-4480 2350);
DISPLAY 0.617021 (-4480 2350);
PAINT SKYBLUE (-4480 2350);
FORCEPROP 1 LAST PART_NUMBER G21796-026
J 0
(-4485 2150);
DISPLAY 0.617021 (-4485 2150);
PAINT BLUE (-4485 2150);
FORCEPROP 1 LAST LOCATION R3P64
J 0
(-4480 2400);
DISPLAY 0.617021 (-4480 2400);
PAINT AQUA (-4480 2400);
FORCEPROP 1 LAST MATERIAL EMPTY
J 0
(-4485 2200);
DISPLAY 0.617021 (-4485 2200);
PAINT RED (-4485 2200);
FORCEPROP 1 LAST PATH I23
J 0
(-4475 2450);
DISPLAY 0.978723 (-4475 2450);
PAINT WHITE (-4475 2450);
DISPLAY INVISIBLE (-4475 2450);
FORCEPROP 0 LAST SEC 1
J 0
(-4475 2450);
DISPLAY 0.680851 (-4475 2450);
PAINT MONO (-4475 2450);
DISPLAY INVISIBLE (-4475 2450);
FORCEPROP 2 LAST SEC_TYPE 0402
J 0
(-4475 2500);
DISPLAY 1.021277 (-4475 2500);
PAINT ORANGE (-4475 2500);
DISPLAY INVISIBLE (-4475 2500);
FORCEPROP 2 LAST CDS_LIB mstr_discrete
J 0
(-4525 2275);
PAINT ORANGE (-4525 2275);
DISPLAY INVISIBLE (-4525 2275);
FORCEADD GND..1
(-4525 2050);
FORCEPROP 3 LASTPIN (-4525 2100) SIG_NAME GND\g
J 0
(-4515 2110);
DISPLAY 0.659574 (-4515 2110);
PAINT MONO (-4515 2110);
DISPLAY INVISIBLE (-4515 2110);
FORCEPROP 1 LAST PATH I24
J 0
(-4450 2050);
DISPLAY 0.872340 (-4450 2050);
PAINT AQUA (-4450 2050);
DISPLAY INVISIBLE (-4450 2050);
FORCEPROP 2 LAST CDS_LIB mstr_symbols
J 0
(-4525 2050);
PAINT ORANGE (-4525 2050);
DISPLAY INVISIBLE (-4525 2050);
FORCEPROP 1 LAST SIZE 1B
J 0
(-4450 2000);
DISPLAY 0.872340 (-4450 2000);
PAINT AQUA (-4450 2000);
DISPLAY INVISIBLE (-4450 2000);
FORCEPROP 1 LAST BODY_TYPE PLUMBING
J 0
(-4570 2007);
DISPLAY 0.340426 (-4570 2007);
PAINT GREEN (-4570 2007);
DISPLAY INVISIBLE (-4570 2007);
FORCEPROP 1 LAST HDL_POWER GND
J 0
(-4525 2200);
DISPLAY 0.872340 (-4525 2200);
PAINT GREEN (-4525 2200);
DISPLAY INVISIBLE (-4525 2200);
FORCEPROP 1 LAST VOLTAGE 0.0V
J 0
(-4570 2007);
DISPLAY 0.340426 (-4570 2007);
PAINT SKYBLUE (-4570 2007);
DISPLAY INVISIBLE (-4570 2007);
FORCEADD P3V3_STBY..1
(-4525 2975);
FORCEPROP 3 LASTPIN (-4525 2925) SIG_NAME P3V3_STBY\g
J 0
(-4515 2935);
DISPLAY 0.659574 (-4515 2935);
PAINT MONO (-4515 2935);
DISPLAY INVISIBLE (-4515 2935);
FORCEPROP 1 LAST SIZE 1B
J 0
(-4480 2997);
DISPLAY 0.340426 (-4480 2997);
PAINT GREEN (-4480 2997);
DISPLAY INVISIBLE (-4480 2997);
FORCEPROP 1 LAST PATH I25
J 0
(-4480 2977);
DISPLAY 0.340426 (-4480 2977);
PAINT GREEN (-4480 2977);
DISPLAY INVISIBLE (-4480 2977);
FORCEPROP 1 LAST BODY_TYPE PLUMBING
J 0
(-4570 2932);
DISPLAY 0.340426 (-4570 2932);
PAINT GREEN (-4570 2932);
DISPLAY INVISIBLE (-4570 2932);
FORCEPROP 2 LAST CDS_LIB mstr_symbols
J 0
(-4525 2975);
PAINT ORANGE (-4525 2975);
DISPLAY INVISIBLE (-4525 2975);
FORCEPROP 1 LAST HDL_POWER P3V3_STBY
J 0
(-4825 2850);
DISPLAY 0.872340 (-4825 2850);
PAINT ORANGE (-4825 2850);
DISPLAY INVISIBLE (-4825 2850);
FORCEPROP 1 LAST VOLTAGE 3.3V
J 0
(-4570 2932);
DISPLAY 0.340426 (-4570 2932);
PAINT SKYBLUE (-4570 2932);
DISPLAY INVISIBLE (-4570 2932);
FORCEADD OFFPAGE..2
(-3375 2475);
FORCEPROP 2 LAST $XR0 120 
J 0
(-3186 2475);
DISPLAY 0.638298 (-3186 2475);
PAINT MONO (-3186 2475);
FORCEPROP 1 LAST COMMENT_BODY TRUE
J 0
(-3420 2380);
DISPLAY 0.872340 (-3420 2380);
PAINT GREEN (-3420 2380);
DISPLAY INVISIBLE (-3420 2380);
FORCEPROP 2 LAST CDS_LIB mstr_standard
J 0
(-3375 2475);
PAINT ORANGE (-3375 2475);
DISPLAY INVISIBLE (-3375 2475);
FORCEPROP 2 LAST PATH I26
J 0
(-3325 2550);
DISPLAY 1.021277 (-3325 2550);
PAINT ORANGE (-3325 2550);
DISPLAY INVISIBLE (-3325 2550);
FORCEPROP 1 LAST OFFPAGE TRUE
J 0
(-3050 2350);
DISPLAY 0.872340 (-3050 2350);
PAINT GREEN (-3050 2350);
DISPLAY INVISIBLE (-3050 2350);
FORCEADD GND..1
(-6200 2100);
FORCEPROP 3 LASTPIN (-6200 2150) SIG_NAME GND\g
J 0
(-6190 2160);
DISPLAY 0.659574 (-6190 2160);
PAINT MONO (-6190 2160);
DISPLAY INVISIBLE (-6190 2160);
FORCEPROP 1 LAST PATH I5
J 0
(-6125 2100);
DISPLAY 0.872340 (-6125 2100);
PAINT AQUA (-6125 2100);
DISPLAY INVISIBLE (-6125 2100);
FORCEPROP 1 LAST SIZE 1B
J 0
(-6125 2050);
DISPLAY 1.170213 (-6125 2050);
PAINT AQUA (-6125 2050);
DISPLAY INVISIBLE (-6125 2050);
FORCEPROP 2 LAST BOM_COST SB
J 0
(-6175 2175);
DISPLAY 1.361702 (-6175 2175);
PAINT ORANGE (-6175 2175);
DISPLAY INVISIBLE (-6175 2175);
FORCEPROP 1 LAST BODY_TYPE PLUMBING
J 0
(-6245 2057);
DISPLAY 0.340426 (-6245 2057);
PAINT GREEN (-6245 2057);
DISPLAY INVISIBLE (-6245 2057);
FORCEPROP 2 LAST CDS_LIB mstr_symbols
J 0
(-6200 2100);
PAINT ORANGE (-6200 2100);
DISPLAY INVISIBLE (-6200 2100);
FORCEPROP 2 LAST ROOM SB
J 0
(-6175 2175);
DISPLAY 1.361702 (-6175 2175);
PAINT ORANGE (-6175 2175);
DISPLAY INVISIBLE (-6175 2175);
FORCEPROP 1 LAST HDL_POWER GND
J 0
(-6200 2250);
DISPLAY 1.170213 (-6200 2250);
PAINT GREEN (-6200 2250);
DISPLAY INVISIBLE (-6200 2250);
FORCEPROP 1 LAST VOLTAGE 0.0V
J 0
(-6245 2057);
DISPLAY 0.340426 (-6245 2057);
PAINT SKYBLUE (-6245 2057);
DISPLAY INVISIBLE (-6245 2057);
FORCEADD RES..2
(-6200 2350);
FORCEPROP 1 LASTPIN (-6200 2450) $PN 1
J 0
(-6195 2412);
DISPLAY 0.617021 (-6195 2412);
PAINT ORANGE (-6195 2412);
FORCEPROP 1 LASTPIN (-6200 2250) $PN 2
J 0
(-6195 2260);
DISPLAY 0.617021 (-6195 2260);
PAINT ORANGE (-6195 2260);
FORCEPROP 1 LAST WATTAGE 1/16W
J 0
(-6160 2325);
DISPLAY 0.617021 (-6160 2325);
PAINT SKYBLUE (-6160 2325);
FORCEPROP 1 LAST PACK_TYPE 0402
J 0
(-6160 2175);
DISPLAY 0.617021 (-6160 2175);
PAINT SKYBLUE (-6160 2175);
FORCEPROP 1 LAST TOLERANCE 1%
J 0
(-6155 2375);
DISPLAY 0.617021 (-6155 2375);
PAINT SKYBLUE (-6155 2375);
FORCEPROP 1 LAST VALUE 1.00K
J 0
(-6155 2425);
DISPLAY 0.617021 (-6155 2425);
PAINT SKYBLUE (-6155 2425);
FORCEPROP 1 LAST LOCATION R7D19
J 0
(-6155 2475);
DISPLAY 0.617021 (-6155 2475);
PAINT AQUA (-6155 2475);
FORCEPROP 1 LAST MATERIAL EMPTY
J 0
(-6160 2275);
DISPLAY 0.617021 (-6160 2275);
PAINT RED (-6160 2275);
FORCEPROP 1 LAST PART_NUMBER G21796-026
J 0
(-6160 2225);
DISPLAY 0.617021 (-6160 2225);
PAINT BLUE (-6160 2225);
FORCEPROP 2 LAST SEC 1
J 0
(-6150 2575);
DISPLAY 0.680851 (-6150 2575);
PAINT MONO (-6150 2575);
DISPLAY INVISIBLE (-6150 2575);
FORCEPROP 2 LAST SEC_TYPE 0402
J 0
(-6150 2575);
DISPLAY 1.021277 (-6150 2575);
PAINT ORANGE (-6150 2575);
DISPLAY INVISIBLE (-6150 2575);
FORCEPROP 1 LAST PATH I6
J 0
(-6150 2525);
DISPLAY 0.978723 (-6150 2525);
PAINT WHITE (-6150 2525);
DISPLAY INVISIBLE (-6150 2525);
FORCEPROP 2 LAST BOM_COST SB
J 0
(-6150 2525);
DISPLAY 1.361702 (-6150 2525);
PAINT ORANGE (-6150 2525);
DISPLAY INVISIBLE (-6150 2525);
FORCEPROP 2 LAST CDS_LOCATION R7D19
J 0
(-6155 2475);
DISPLAY 0.617021 (-6155 2475);
PAINT AQUA (-6155 2475);
DISPLAY INVISIBLE (-6155 2475);
FORCEPROP 2 LAST CDS_LIB mstr_discrete
J 0
(-6200 2350);
PAINT ORANGE (-6200 2350);
DISPLAY INVISIBLE (-6200 2350);
FORCEPROP 2 LAST ROOM SB
J 0
(-6150 2525);
DISPLAY 1.361702 (-6150 2525);
PAINT ORANGE (-6150 2525);
DISPLAY INVISIBLE (-6150 2525);
FORCEADD P3V3_STBY..1
(-6200 3000);
FORCEPROP 3 LASTPIN (-6200 2950) SIG_NAME P3V3_STBY\g
J 0
(-6190 2960);
DISPLAY 0.659574 (-6190 2960);
PAINT MONO (-6190 2960);
DISPLAY INVISIBLE (-6190 2960);
FORCEPROP 1 LAST PATH I7
J 0
(-6155 3002);
DISPLAY 0.340426 (-6155 3002);
PAINT GREEN (-6155 3002);
DISPLAY INVISIBLE (-6155 3002);
FORCEPROP 1 LAST BODY_TYPE PLUMBING
J 0
(-6245 2957);
DISPLAY 0.340426 (-6245 2957);
PAINT GREEN (-6245 2957);
DISPLAY INVISIBLE (-6245 2957);
FORCEPROP 2 LAST CDS_LIB mstr_symbols
J 0
(-6200 3000);
PAINT ORANGE (-6200 3000);
DISPLAY INVISIBLE (-6200 3000);
FORCEPROP 1 LAST SIZE 1B
J 0
(-6155 3022);
DISPLAY 0.340426 (-6155 3022);
PAINT GREEN (-6155 3022);
DISPLAY INVISIBLE (-6155 3022);
FORCEPROP 1 LAST HDL_POWER P3V3_STBY
J 0
(-6500 2875);
DISPLAY 0.872340 (-6500 2875);
PAINT ORANGE (-6500 2875);
DISPLAY INVISIBLE (-6500 2875);
FORCEPROP 1 LAST VOLTAGE 3.3V
J 0
(-6245 2957);
DISPLAY 0.340426 (-6245 2957);
PAINT SKYBLUE (-6245 2957);
DISPLAY INVISIBLE (-6245 2957);
FORCEADD OFFPAGE..5
(-7150 2575);
FORCEPROP 2 LAST $XR2 200 
J 0
(-7645 2575);
DISPLAY 0.638298 (-7645 2575);
PAINT MONO (-7645 2575);
FORCEPROP 2 LAST $XR1 145 
J 0
(-7525 2575);
DISPLAY 0.638298 (-7525 2575);
PAINT MONO (-7525 2575);
FORCEPROP 2 LAST $XR0 120 
J 0
(-7405 2575);
DISPLAY 0.638298 (-7405 2575);
PAINT MONO (-7405 2575);
FORCEPROP 2 LAST ROOM SB
J 0
(-7425 2625);
DISPLAY 1.361702 (-7425 2625);
PAINT ORANGE (-7425 2625);
DISPLAY INVISIBLE (-7425 2625);
FORCEPROP 2 LAST BOM_COST SB
J 0
(-7425 2625);
DISPLAY 1.361702 (-7425 2625);
PAINT ORANGE (-7425 2625);
DISPLAY INVISIBLE (-7425 2625);
FORCEPROP 2 LAST PATH I8
J 0
(-7100 2650);
DISPLAY 1.021277 (-7100 2650);
PAINT ORANGE (-7100 2650);
DISPLAY INVISIBLE (-7100 2650);
FORCEPROP 1 LAST COMMENT_BODY TRUE
J 0
(-7050 2500);
DISPLAY 1.170213 (-7050 2500);
PAINT GREEN (-7050 2500);
DISPLAY INVISIBLE (-7050 2500);
FORCEPROP 1 LAST OFFPAGE TRUE
J 0
(-6825 2450);
DISPLAY 1.170213 (-6825 2450);
PAINT GREEN (-6825 2450);
DISPLAY INVISIBLE (-6825 2450);
FORCEPROP 2 LAST CDS_LIB mstr_standard
J 0
(-7150 2575);
PAINT ORANGE (-7150 2575);
DISPLAY INVISIBLE (-7150 2575);
FORCEADD P3V3_STBY..1
(-6325 4400);
FORCEPROP 3 LASTPIN (-6325 4350) SIG_NAME P3V3_STBY\g
J 0
(-6315 4360);
DISPLAY 0.659574 (-6315 4360);
PAINT MONO (-6315 4360);
DISPLAY INVISIBLE (-6315 4360);
FORCEPROP 1 LAST PATH I9
J 0
(-6280 4402);
DISPLAY 0.340426 (-6280 4402);
PAINT GREEN (-6280 4402);
DISPLAY INVISIBLE (-6280 4402);
FORCEPROP 1 LAST BODY_TYPE PLUMBING
J 0
(-6370 4357);
DISPLAY 0.340426 (-6370 4357);
PAINT GREEN (-6370 4357);
DISPLAY INVISIBLE (-6370 4357);
FORCEPROP 1 LAST SIZE 1B
J 0
(-6280 4422);
DISPLAY 0.340426 (-6280 4422);
PAINT GREEN (-6280 4422);
DISPLAY INVISIBLE (-6280 4422);
FORCEPROP 2 LAST CDS_LIB mstr_symbols
J 0
(-6325 4400);
PAINT ORANGE (-6325 4400);
DISPLAY INVISIBLE (-6325 4400);
FORCEPROP 1 LAST HDL_POWER P3V3_STBY
J 0
(-6625 4275);
DISPLAY 0.872340 (-6625 4275);
PAINT ORANGE (-6625 4275);
DISPLAY INVISIBLE (-6625 4275);
FORCEPROP 1 LAST VOLTAGE 3.3V
J 0
(-6370 4357);
DISPLAY 0.340426 (-6370 4357);
PAINT SKYBLUE (-6370 4357);
DISPLAY INVISIBLE (-6370 4357);
FORCEADD DNS..2
(-4520 2720);
PAINT RED (-4520 2720);
FORCEPROP 2 LAST CDS_LIB mstr_misc
J 0
(-4520 2720);
PAINT ORANGE (-4520 2720);
DISPLAY INVISIBLE (-4520 2720);
FORCEPROP 1 LAST COMMENT_BODY TRUE
R 1
J 0
(-4445 2495);
DISPLAY 0.872340 (-4445 2495);
PAINT GREEN (-4445 2495);
DISPLAY INVISIBLE (-4445 2495);
FORCEADD DESIGN_NOTE..1
(-7675 2000);
FORCEPROP 0 LAST L3 LT KEY DOWNGRADE ENABLED WHEN LOW
J 0
(-7875 1800);
DISPLAY 1.021277 (-7875 1800);
PAINT ORANGE (-7875 1800);
FORCEPROP 0 LAST L1 PCH INTERNAL PULL-UP
J 0
(-7875 1725);
DISPLAY 1.021277 (-7875 1725);
PAINT ORANGE (-7875 1725);
FORCEPROP 0 LAST L4 NORMAL OC DETECT ENABLE FUNCTIONALITY RESUMES AFTER RSMRST# DEASSERTS
J 0
(-7875 1650);
DISPLAY 1.021277 (-7875 1650);
PAINT ORANGE (-7875 1650);
FORCEPROP 0 LAST L2 LT KEY DOWNGRADE DISABLED WHEN HIGH (DEFAULT)
J 0
(-7875 1875);
DISPLAY 1.021277 (-7875 1875);
PAINT ORANGE (-7875 1875);
FORCEPROP 1 LAST COMMENT_BODY TRUE
J 0
(-7650 2100);
DISPLAY 1.319149 (-7650 2100);
PAINT ORANGE (-7650 2100);
DISPLAY INVISIBLE (-7650 2100);
FORCEPROP 2 LAST BOM_COST SB
J 0
(-7550 1900);
DISPLAY 1.361702 (-7550 1900);
PAINT ORANGE (-7550 1900);
DISPLAY INVISIBLE (-7550 1900);
FORCEPROP 2 LAST CDS_LIB mstr_symbols
J 0
(-7675 2000);
PAINT ORANGE (-7675 2000);
DISPLAY INVISIBLE (-7675 2000);
FORCEPROP 2 LAST ROOM SB_HEADERS
J 0
(-7550 1900);
DISPLAY 1.361702 (-7550 1900);
PAINT ORANGE (-7550 1900);
DISPLAY INVISIBLE (-7550 1900);
FORCEADD DESIGN_NOTE..1
(-4200 2025);
FORCEPROP 0 LAST L1 PCH INTERNAL PULL-DOWN
J 0
(-4375 1750);
DISPLAY 1.021277 (-4375 1750);
PAINT ORANGE (-4375 1750);
FORCEPROP 0 LAST L3 MASTER ATTACHED FLASH WHEN LOW (DEFAULT)
J 0
(-4375 1825);
DISPLAY 1.021277 (-4375 1825);
PAINT ORANGE (-4375 1825);
FORCEPROP 0 LAST L2 SLAVE ATTACHED FLASH WHEN HIGH
J 0
(-4375 1900);
DISPLAY 1.021277 (-4375 1900);
PAINT ORANGE (-4375 1900);
FORCEPROP 0 LAST L4 INTERNAL PULL DOWN DISABLED AFTER RSMRST# DEASSERTS
J 0
(-4375 1675);
DISPLAY 1.021277 (-4375 1675);
PAINT ORANGE (-4375 1675);
FORCEPROP 2 LAST ROOM SB_HEADERS
J 0
(-4075 1925);
DISPLAY 1.361702 (-4075 1925);
PAINT ORANGE (-4075 1925);
DISPLAY INVISIBLE (-4075 1925);
FORCEPROP 1 LAST COMMENT_BODY TRUE
J 0
(-4175 2125);
DISPLAY 1.319149 (-4175 2125);
PAINT ORANGE (-4175 2125);
DISPLAY INVISIBLE (-4175 2125);
FORCEPROP 2 LAST BOM_COST SB
J 0
(-4075 1925);
DISPLAY 1.361702 (-4075 1925);
PAINT ORANGE (-4075 1925);
DISPLAY INVISIBLE (-4075 1925);
FORCEPROP 2 LAST CDS_LIB mstr_symbols
J 0
(-4200 2025);
PAINT ORANGE (-4200 2025);
DISPLAY INVISIBLE (-4200 2025);
FORCEADD DESIGN_NOTE..1
(-4750 3575);
FORCEPROP 0 LAST L4 NORMAL SML ALERT# FUNCTIONALITY RESUMES AFTER RSMRST# DEASSERTS
J 0
(-4950 3200);
DISPLAY 1.021277 (-4950 3200);
PAINT ORANGE (-4950 3200);
FORCEPROP 0 LAST L3 LPC WHEN LOW (DEFAULT)
J 0
(-4950 3350);
DISPLAY 1.021277 (-4950 3350);
PAINT ORANGE (-4950 3350);
FORCEPROP 0 LAST L1 PCH INTERNAL PULL-DOWN
J 0
(-4950 3275);
DISPLAY 1.021277 (-4950 3275);
PAINT ORANGE (-4950 3275);
FORCEPROP 0 LAST L2 ESPI WHEN HIGH
J 0
(-4950 3425);
DISPLAY 1.021277 (-4950 3425);
PAINT ORANGE (-4950 3425);
FORCEPROP 1 LAST COMMENT_BODY TRUE
J 0
(-4725 3675);
DISPLAY 1.319149 (-4725 3675);
PAINT ORANGE (-4725 3675);
DISPLAY INVISIBLE (-4725 3675);
FORCEPROP 2 LAST CDS_LIB mstr_symbols
J 0
(-4750 3575);
PAINT ORANGE (-4750 3575);
DISPLAY INVISIBLE (-4750 3575);
FORCEPROP 2 LAST BOM_COST SB
J 0
(-4625 3475);
DISPLAY 1.361702 (-4625 3475);
PAINT ORANGE (-4625 3475);
DISPLAY INVISIBLE (-4625 3475);
FORCEPROP 2 LAST ROOM SB_HEADERS
J 0
(-4625 3475);
DISPLAY 1.361702 (-4625 3475);
PAINT ORANGE (-4625 3475);
DISPLAY INVISIBLE (-4625 3475);
FORCEADD DNS..2
(-6195 2345);
PAINT RED (-6195 2345);
FORCEPROP 2 LAST CDS_LIB mstr_misc
J 0
(-6195 2345);
PAINT ORANGE (-6195 2345);
DISPLAY INVISIBLE (-6195 2345);
FORCEPROP 1 LAST COMMENT_BODY TRUE
R 1
J 0
(-6120 2120);
DISPLAY 0.872340 (-6120 2120);
PAINT GREEN (-6120 2120);
DISPLAY INVISIBLE (-6120 2120);
FORCEADD DNS..2
(-4520 2270);
PAINT RED (-4520 2270);
FORCEPROP 2 LAST CDS_LIB mstr_misc
J 0
(-4520 2270);
PAINT ORANGE (-4520 2270);
DISPLAY INVISIBLE (-4520 2270);
FORCEPROP 1 LAST COMMENT_BODY TRUE
R 1
J 0
(-4445 2045);
DISPLAY 0.872340 (-4445 2045);
PAINT GREEN (-4445 2045);
DISPLAY INVISIBLE (-4445 2045);
FORCEADD DESIGN_NOTE..1
(-7675 3875);
FORCEPROP 0 LAST L3 REAR USB3 PORT ENABLED BY DEFAULT (DCI DISABLED)
J 0
(-7875 3575);
DISPLAY 1.021277 (-7875 3575);
PAINT ORANGE (-7875 3575);
FORCEPROP 0 LAST L4 CHANGE TO 1M FOR DCI FUNCTIONALITY (REAR USB3 DISABLED)
J 0
(-7875 3500);
DISPLAY 1.021277 (-7875 3500);
PAINT ORANGE (-7875 3500);
FORCEPROP 0 LAST L1 PCH INTERNAL PULL-DOWN, DISABLED AFTER STRAP SAMPLING
J 0
(-7875 3650);
DISPLAY 1.021277 (-7875 3650);
PAINT ORANGE (-7875 3650);
FORCEPROP 0 LAST L2 EXI BOOT STALL BYPASS DISABLED WHEN LOW (DEFAULT)
J 0
(-7875 3725);
DISPLAY 1.021277 (-7875 3725);
PAINT ORANGE (-7875 3725);
FORCEPROP 1 LAST COMMENT_BODY TRUE
J 0
(-7650 3975);
DISPLAY 1.319149 (-7650 3975);
PAINT ORANGE (-7650 3975);
DISPLAY INVISIBLE (-7650 3975);
FORCEPROP 2 LAST BOM_COST SB
J 0
(-7550 3775);
DISPLAY 1.361702 (-7550 3775);
PAINT ORANGE (-7550 3775);
DISPLAY INVISIBLE (-7550 3775);
FORCEPROP 2 LAST CDS_LIB mstr_symbols
J 0
(-7675 3875);
PAINT ORANGE (-7675 3875);
DISPLAY INVISIBLE (-7675 3875);
FORCEPROP 2 LAST ROOM SB_HEADERS
J 0
(-7550 3775);
DISPLAY 1.361702 (-7550 3775);
PAINT ORANGE (-7550 3775);
DISPLAY INVISIBLE (-7550 3775);
FORCEADD INTEL_CORP_BPAGE..1
(0 0);
FORCEPROP 1 LAST CDS_CON_LAST_MODIFIED Tue Dec 01 11:51:59 2015
J 0
(-1425 325);
PAINT ORANGE (-1425 325);
DISPLAY INVISIBLE (-1425 325);
FORCEPROP 1 LAST CUSTOM_TXT_CDS <CURRENT_DESIGN_SHEET> OF <TOTAL_DESIGN_SHEETS>
J 0
(-500 25);
PAINT GREEN (-500 25);
FORCEPROP 1 LAST CUSTOM_TXT_CDS <CON_LAST_MODIFIED>
J 0
(-1925 350);
PAINT GREEN (-1925 350);
FORCEPROP 2 LAST CUSTOM_TXT_CDS <XR_PAGE_TITLE>
J 0
(-7890 5250);
DISPLAY 0.638298 (-7890 5250);
PAINT PINK (-7890 5250);
DISPLAY INVISIBLE (-7890 5250);
FORCEPROP 1 LAST SCH_NUMBER H4694802
J 0
(-1300 150);
DISPLAY 1.212766 (-1300 150);
PAINT YELLOW (-1300 150);
FORCEPROP 1 LAST SCH_DEPT BESD
J 1
(-4450 100);
DISPLAY 1.212766 (-4450 100);
PAINT YELLOW (-4450 100);
FORCEPROP 1 LAST SCH_REV 2.420
J 0
(-250 150);
DISPLAY 0.978723 (-250 150);
PAINT YELLOW (-250 150);
FORCEPROP 1 LAST SCH_TITLE PCH STRAPS (2/2)
J 0
(-7950 50);
DISPLAY 1.212766 (-7950 50);
PAINT ORANGE (-7950 50);
FORCEPROP 1 LAST SCH_ADDRESS1 2200 Mission College Blvd.
J 0
(-3975 125);
DISPLAY 0.617021 (-3975 125);
PAINT GREEN (-3975 125);
FORCEPROP 1 LAST SCH_ADDRESS2 P.O. BOX 58119
J 0
(-3975 75);
DISPLAY 0.617021 (-3975 75);
PAINT GREEN (-3975 75);
FORCEPROP 1 LAST SCH_ADDRESS3 Santa Clara, CA 95052-8119
J 0
(-3975 25);
DISPLAY 0.617021 (-3975 25);
PAINT GREEN (-3975 25);
FORCEPROP 1 LAST COMMENT_BODY TRUE
J 0
(12 12);
DISPLAY 0.510638 (12 12);
PAINT GREEN (12 12);
DISPLAY INVISIBLE (12 12);
FORCEPROP 2 LAST CDS_LIB mstr_symbols
J 0
(0 0);
PAINT ORANGE (0 0);
DISPLAY INVISIBLE (0 0);
FORCEPROP 2 LAST PAGE_BORDER TRUE
J 0
(-7890 5250);
DISPLAY 1.021277 (-7890 5250);
PAINT PINK (-7890 5250);
DISPLAY INVISIBLE (-7890 5250);
FORCEPROP 2 LAST CDS_XR_PAGE_TITLE CR-126 : @BASEBOARD_FAB2_LIB.BASEBOARD_FAB2(SCH_1):PAGE126
J 0
(-7890 5250);
DISPLAY 0.638298 (-7890 5250);
PAINT PINK (-7890 5250);
DISPLAY INVISIBLE (-7890 5250);
WIRE 16 -1 (-3625 3725)(-3625 3625);
WIRE 16 -1 (-3625 4600)(-3625 4525);
WIRE 16 -1 (-4525 2175)(-4525 2100);
WIRE 16 -1 (-4525 2925)(-4525 2825);
WIRE 16 -1 (-6200 2250)(-6200 2150);
WIRE 16 -1 (-6200 2950)(-6200 2875);
WIRE 16 -1 (-6325 4350)(-6325 4275);
WIRE 16 273 (-1350 1625)(-1350 3150);
WIRE 16 273 (-5100 1625)(-1350 1625);
WIRE 16 273 (-1350 3150)(-2275 3150);
WIRE 16 273 (-5150 1625)(-5150 3425);
WIRE 16 273 (-7900 1625)(-5150 1625);
WIRE 16 -1 (-4525 2625)(-4525 2475);
WIRE 16 -1 (-4525 2475)(-3425 2475);
FORCEPROP 2 LAST SIG_NAME FM_FLASH_ATTACH_CFG_STRAP
J 0
(-4110 2485);
DISPLAY 0.617021 (-4110 2485);
PAINT ORANGE (-4110 2485);
WIRE 16 -1 (-4525 2375)(-4525 2475);
WIRE 16 -1 (-3825 3825)(-4425 3825);
FORCEPROP 2 LAST SIG_NAME RST_RSMRST_DLY
J 0
(-4385 3835);
DISPLAY 0.617021 (-4385 3835);
PAINT ORANGE (-4385 3835);
WIRE 16 273 (-2325 3150)(-2325 4950);
WIRE 16 273 (-5075 3150)(-2325 3150);
WIRE 16 -1 (-3625 4225)(-2950 4225);
FORCEPROP 2 LAST SIG_NAME IRQ_SML0_ALERT_N
J 0
(-3335 4235);
DISPLAY 0.617021 (-3335 4235);
PAINT ORANGE (-3335 4235);
WIRE 16 -1 (-3625 4225)(-3625 4125);
WIRE 16 -1 (-3625 4325)(-3625 4225);
WIRE 16 -1 (-7100 2575)(-6200 2575);
FORCEPROP 0 LAST SIG_NAME FM_OC_DETECT_EN_N
J 0
(-7060 2585);
DISPLAY 0.617021 (-7060 2585);
PAINT ORANGE (-7060 2585);
WIRE 16 -1 (-6200 2675)(-6200 2575);
WIRE 16 -1 (-6200 2450)(-6200 2575);
WIRE 16 -1 (-7300 4025)(-6325 4025);
FORCEPROP 0 LAST SIG_NAME FM_PCH_BMC_THERMTRIP_EXI_STRAP_N
J 0
(-7285 4035);
DISPLAY 0.617021 (-7285 4035);
PAINT ORANGE (-7285 4035);
WIRE 16 -1 (-6325 4075)(-6325 4025);
WIRE 16 273 (-7925 3450)(-5150 3450);
WIRE 16 273 (-5150 3450)(-5150 4875);
DOT 1 (-6200 2575);
DOT 1 (-4525 2475);
DOT 1 (-3625 4225);
FORCENOTE
EXI BOOT STALL BYPASS (DFX)
(-7825 4725) 0;
DISPLAY LEFT (-7825 4725);
DISPLAY 2.680851 (-7825 4725);
PAINT PURPLE (-7825 4725);
FORCENOTE
0
(-3000 4525) 0;
DISPLAY LEFT (-3000 4525);
DISPLAY 8.255319 (-3000 4525);
PAINT PURPLE (-3000 4525);
FORCENOTE
0
(-1975 2625) 0;
DISPLAY LEFT (-1975 2625);
DISPLAY 8.255319 (-1975 2625);
PAINT PURPLE (-1975 2625);
FORCENOTE
0
(-5650 4300) 0;
DISPLAY LEFT (-5650 4300);
DISPLAY 8.255319 (-5650 4300);
PAINT PURPLE (-5650 4300);
FORCENOTE
ESPI OR LPC
(-5025 4700) 0;
DISPLAY LEFT (-5025 4700);
DISPLAY 2.680851 (-5025 4700);
PAINT PURPLE (-5025 4700);
FORCENOTE
BIOS FLASH ATTACHMENT
(-4125 2825) 0;
DISPLAY LEFT (-4125 2825);
DISPLAY 2.680851 (-4125 2825);
PAINT PURPLE (-4125 2825);
FORCENOTE
CONFIGURATION
(-4125 2675) 0;
DISPLAY LEFT (-4125 2675);
DISPLAY 2.680851 (-4125 2675);
PAINT PURPLE (-4125 2675);
FORCENOTE
LT KEY DOWNGRADE
(-7775 3175) 0;
DISPLAY LEFT (-7775 3175);
DISPLAY 2.680851 (-7775 3175);
PAINT PURPLE (-7775 3175);
FORCENOTE
1
(-5625 2975) 0;
DISPLAY LEFT (-5625 2975);
DISPLAY 8.255319 (-5625 2975);
PAINT PURPLE (-5625 2975);
QUIT
